(kicad_pcb
	(version 20260206)
	(generator "pcbnew")
	(generator_version "10.0")
	(general
		(thickness 1.6)
		(legacy_teardrops no)
	)
	(paper "A4")
	(title_block
		(title "v2-pdb — ms_pdb_v2.brd")
		(comment 1 "Open CloudServer (Microsoft) / footprints 281-282 of 348")
	)
	(layers
		(0 "F.Cu" signal "TOP")
		(4 "In1.Cu" signal "GND")
		(6 "In2.Cu" signal "IN1")
		(8 "In3.Cu" signal "VCC")
		(10 "In4.Cu" signal "VCC1")
		(12 "In5.Cu" signal "IN2")
		(14 "In6.Cu" signal "GND1")
		(2 "B.Cu" signal "BOTTOM")
		(9 "F.Adhes" user "F.Adhesive")
		(11 "B.Adhes" user "B.Adhesive")
		(13 "F.Paste" user "Package Geometry/Pastemask Top")
		(15 "B.Paste" user "Package Geometry/Pastemask Bottom")
		(5 "F.SilkS" user "Ref Des/Silkscreen Top")
		(7 "B.SilkS" user "Ref Des/Silkscreen Bottom")
		(1 "F.Mask" user "Board Geometry/Soldermask Top")
		(3 "B.Mask" user "Board Geometry/Soldermask Bottom")
		(17 "Dwgs.User" user "User.Drawings")
		(19 "Cmts.User" user "User.Comments")
		(21 "Eco1.User" user "User.Eco1")
		(23 "Eco2.User" user "User.Eco2")
		(25 "Edge.Cuts" user "Board Geometry/Outline")
		(27 "Margin" user)
		(31 "F.CrtYd" user "Package Geometry/Place Bound Top")
		(29 "B.CrtYd" user "Package Geometry/Place Bound Bottom")
		(35 "F.Fab" user "Ref Des/Assembly Top")
		(33 "B.Fab" user "Ref Des/Assembly Bottom")
	)
	(footprint ""
		(layer "F.Cu")
		(at 26.226008 -453.535034)
		(property "Reference" "R60"
			(at -3.522472 -0.815594 0)
			(unlocked yes)
			(layer "F.SilkS")
			(effects
				(font
					(size 0.7874 0.5842)
					(thickness 0.1524)
				)
				(justify left)
			)
		)
		(property "Value" ""
			(at 0 0 0)
			(layer "F.Fab")
			(effects
				(font
					(size 1.27 1.27)
				)
			)
		)
		(duplicate_pad_numbers_are_jumpers no)
		(fp_line
			(start -0.7874 -0.4064)
			(end 0.7874 -0.4064)
			(stroke
				(width 0.1524)
				(type default)
			)
			(layer "F.SilkS")
		)
		(fp_line
			(start -0.7874 0.4064)
			(end -0.7874 -0.4064)
			(stroke
				(width 0.1524)
				(type default)
			)
			(layer "F.SilkS")
		)
		(fp_line
			(start 0.7874 -0.4064)
			(end 0.7874 0.4064)
			(stroke
				(width 0.1524)
				(type default)
			)
			(layer "F.SilkS")
		)
		(fp_line
			(start 0.7874 0.4064)
			(end -0.7874 0.4064)
			(stroke
				(width 0.1524)
				(type default)
			)
			(layer "F.SilkS")
		)
		(fp_poly
			(pts
				(xy -0.508 0.2794) (xy -0.508 0.2286) (xy -0.635 0.2286) (xy -0.635 -0.254) (xy -0.5334 -0.254)
				(xy -0.5334 -0.2794) (xy 0.5334 -0.2794) (xy 0.5334 -0.254) (xy 0.635 -0.254) (xy 0.635 0.254) (xy 0.5334 0.254)
				(xy 0.5334 0.2794)
			)
			(stroke
				(width 0)
				(type default)
			)
			(fill no)
			(layer "F.CrtYd")
		)
		(pad "1" smd rect
			(at 0.40005 0)
			(size 0.4572 0.508)
			(layers "F.Cu" "F.Mask" "F.Paste")
			(net "PSU6_PS_KILL")
		)
		(pad "2" smd rect
			(at -0.40005 0)
			(size 0.4572 0.508)
			(layers "F.Cu" "F.Mask" "F.Paste")
			(net "GND")
		)
	)
	(footprint ""
		(layer "F.Cu")
		(at 30.45968 -83.330034)
		(property "Reference" "J1"
			(at 7.517892 2.350516 0)
			(unlocked yes)
			(layer "F.SilkS")
			(effects
				(font
					(size 0.7874 0.5842)
					(thickness 0.1524)
				)
				(justify left)
			)
		)
		(property "Value" ""
			(at 0 0 0)
			(layer "F.Fab")
			(effects
				(font
					(size 1.27 1.27)
				)
			)
		)
		(duplicate_pad_numbers_are_jumpers no)
		(fp_line
			(start -2.135124 -4.560062)
			(end -2.135124 83.300062)
			(stroke
				(width 0.1524)
				(type default)
			)
			(layer "F.SilkS")
		)
		(fp_line
			(start -2.135124 83.300062)
			(end 7.215124 83.300062)
			(stroke
				(width 0.1524)
				(type default)
			)
			(layer "F.SilkS")
		)
		(fp_line
			(start 7.215124 -4.560062)
			(end -2.135124 -4.560062)
			(stroke
				(width 0.1524)
				(type default)
			)
			(layer "F.SilkS")
		)
		(fp_line
			(start 7.215124 83.300062)
			(end 7.215124 -4.560062)
			(stroke
				(width 0.1524)
				(type default)
			)
			(layer "F.SilkS")
		)
		(fp_poly
			(pts
				(xy -2.467864 0.208026) (xy -5.167884 -0.491998) (xy -5.167884 0.90805)
			)
			(stroke
				(width 0)
				(type default)
			)
			(fill yes)
			(layer "F.SilkS")
		)
		(fp_poly
			(pts
				(xy -2.28219 -0.127) (xy -4.98221 -0.827024) (xy -4.98221 0.573024)
			)
			(stroke
				(width 0)
				(type default)
			)
			(fill yes)
			(layer "B.SilkS")
		)
		(fp_poly
			(pts
				(xy -0.8636 -0.8636) (xy -0.8636 79.6036) (xy -0.8636 79.629) (xy 5.9436 79.629) (xy 5.9436 79.6036)
				(xy 5.9436 -0.8636) (xy 5.9436 -0.889) (xy -0.8636 -0.889)
			)
			(stroke
				(width 0)
				(type default)
			)
			(fill no)
			(layer "B.CrtYd")
		)
		(fp_rect
			(start -2.135124 -4.560062)
			(end 7.21487 83.300062)
			(stroke
				(width 0)
				(type default)
			)
			(fill no)
			(layer "F.CrtYd")
		)
		(fp_line
			(start -2.135124 -4.560062)
			(end 7.215124 -4.560062)
			(stroke
				(width 0.1)
				(type default)
			)
			(layer "F.Fab")
		)
		(fp_line
			(start -2.135124 83.300062)
			(end -2.135124 -4.560062)
			(stroke
				(width 0.1)
				(type default)
			)
			(layer "F.Fab")
		)
		(fp_line
			(start 7.215124 -4.560062)
			(end 7.215124 83.300062)
			(stroke
				(width 0.1)
				(type default)
			)
			(layer "F.Fab")
		)
		(fp_line
			(start 7.215124 83.300062)
			(end -2.135124 83.300062)
			(stroke
				(width 0.1)
				(type default)
			)
			(layer "F.Fab")
		)
		(fp_text user "1"
			(at -3.01625 -0.658368 0)
			(unlocked yes)
			(layer "F.SilkS")
			(effects
				(font
					(size 0.7874 0.5842)
					(thickness 0.1524)
				)
				(justify left)
			)
		)
		(fp_text user "32"
			(at -1.971802 79.99095 0)
			(unlocked yes)
			(layer "F.SilkS")
			(effects
				(font
					(size 0.7874 0.5842)
					(thickness 0.1524)
				)
				(justify left)
			)
		)
		(fp_text user "33"
			(at 7.57428 78.22184 0)
			(unlocked yes)
			(layer "F.SilkS")
			(effects
				(font
					(size 0.7874 0.5842)
					(thickness 0.1524)
				)
				(justify left)
			)
		)
		(fp_text user "64"
			(at 7.666736 -0.128016 0)
			(unlocked yes)
			(layer "F.SilkS")
			(effects
				(font
					(size 0.7874 0.5842)
					(thickness 0.1524)
				)
				(justify left)
			)
		)
		(fp_text user "32"
			(at -1.060958 79.574644 0)
			(unlocked yes)
			(layer "B.SilkS")
			(effects
				(font
					(size 0.7874 0.5842)
					(thickness 0.1524)
				)
				(justify left mirror)
			)
		)
		(fp_text user "1"
			(at -1.044448 -0.912622 0)
			(unlocked yes)
			(layer "B.SilkS")
			(effects
				(font
					(size 0.7874 0.5842)
					(thickness 0.1524)
				)
				(justify left mirror)
			)
		)
		(fp_text user "64"
			(at 5.82168 -1.531112 0)
			(unlocked yes)
			(layer "B.SilkS")
			(effects
				(font
					(size 0.7874 0.5842)
					(thickness 0.1524)
				)
				(justify left mirror)
			)
		)
		(fp_text user "33"
			(at 6.15696 80.823308 0)
			(unlocked yes)
			(layer "B.SilkS")
			(effects
				(font
					(size 0.7874 0.5842)
					(thickness 0.1524)
				)
				(justify left mirror)
			)
		)
		(pad "1" thru_hole rect
			(at 0 0 270)
			(size 1.6256 1.6256)
			(drill 1.1176)
			(layers "*.Cu" "*.Mask")
			(remove_unused_layers no)
			(net "P12V")
			(clearance 0)
			(padstack
				(mode front_inner_back)
				(layer "Inner"
					(shape circle)
					(size 1.6256 1.6256)
					(clearance 0)
				)
				(layer "B.Cu"
					(shape rect)
					(size 1.6256 1.6256)
					(clearance 0)
				)
			)
		)
		(pad "2" thru_hole circle
			(at 0 2.54 270)
			(size 1.6256 1.6256)
			(drill 1.1176)
			(layers "*.Cu" "*.Mask")
			(remove_unused_layers no)
			(net "P12V")
			(clearance 0)
		)
		(pad "3" thru_hole circle
			(at 0 5.08 270)
			(size 1.6256 1.6256)
			(drill 1.1176)
			(layers "*.Cu" "*.Mask")
			(remove_unused_layers no)
			(net "P12V")
			(clearance 0)
		)
		(pad "4" thru_hole circle
			(at 0 7.62 270)
			(size 1.6256 1.6256)
			(drill 1.1176)
			(layers "*.Cu" "*.Mask")
			(remove_unused_layers no)
			(net "P12V")
			(clearance 0)
		)
		(pad "5" thru_hole circle
			(at 0 10.16 270)
			(size 1.6256 1.6256)
			(drill 1.1176)
			(layers "*.Cu" "*.Mask")
			(remove_unused_layers no)
			(net "P12V")
			(clearance 0)
		)
		(pad "6" thru_hole circle
			(at 0 12.7 270)
			(size 1.6256 1.6256)
			(drill 1.1176)
			(layers "*.Cu" "*.Mask")
			(remove_unused_layers no)
			(net "P12V")
			(clearance 0)
		)
		(pad "7" thru_hole circle
			(at 0 15.24 270)
			(size 1.6256 1.6256)
			(drill 1.1176)
			(layers "*.Cu" "*.Mask")
			(remove_unused_layers no)
			(net "P12V")
			(clearance 0)
		)
		(pad "8" thru_hole circle
			(at 0 17.78 270)
			(size 1.6256 1.6256)
			(drill 1.1176)
			(layers "*.Cu" "*.Mask")
			(remove_unused_layers no)
			(net "P12V")
			(clearance 0)
		)
		(pad "9" thru_hole circle
			(at 0 20.32 270)
			(size 1.6256 1.6256)
			(drill 1.1176)
			(layers "*.Cu" "*.Mask")
			(remove_unused_layers no)
			(net "P12V")
			(clearance 0)
		)
		(pad "10" thru_hole circle
			(at 0 22.86 270)
			(size 1.6256 1.6256)
			(drill 1.1176)
			(layers "*.Cu" "*.Mask")
			(remove_unused_layers no)
			(net "P12V")
			(clearance 0)
		)
		(pad "11" thru_hole circle
			(at 0 25.4 270)
			(size 1.6256 1.6256)
			(drill 1.1176)
			(layers "*.Cu" "*.Mask")
			(remove_unused_layers no)
			(net "P12V")
			(clearance 0)
		)
		(pad "12" thru_hole circle
			(at 0 27.94 270)
			(size 1.6256 1.6256)
			(drill 1.1176)
			(layers "*.Cu" "*.Mask")
			(remove_unused_layers no)
			(net "P12V")
			(clearance 0)
		)
		(pad "13" thru_hole circle
			(at 0 30.48 270)
			(size 1.6256 1.6256)
			(drill 1.1176)
			(layers "*.Cu" "*.Mask")
			(remove_unused_layers no)
			(net "GND")
			(clearance 0)
		)
		(pad "14" thru_hole circle
			(at 0 33.02 270)
			(size 1.6256 1.6256)
			(drill 1.1176)
			(layers "*.Cu" "*.Mask")
			(remove_unused_layers no)
			(net "GND")
			(clearance 0)
		)
		(pad "15" thru_hole circle
			(at 0 35.56 270)
			(size 1.6256 1.6256)
			(drill 1.1176)
			(layers "*.Cu" "*.Mask")
			(remove_unused_layers no)
			(net "GND")
			(clearance 0)
		)
		(pad "16" thru_hole circle
			(at 0 38.1 270)
			(size 1.6256 1.6256)
			(drill 1.1176)
			(layers "*.Cu" "*.Mask")
			(remove_unused_layers no)
			(net "GND")
			(clearance 0)
		)
		(pad "17" thru_hole circle
			(at 0 40.64 270)
			(size 1.6256 1.6256)
			(drill 1.1176)
			(layers "*.Cu" "*.Mask")
			(remove_unused_layers no)
			(net "GND")
			(clearance 0)
		)
		(pad "18" thru_hole circle
			(at 0 43.18 270)
			(size 1.6256 1.6256)
			(drill 1.1176)
			(layers "*.Cu" "*.Mask")
			(remove_unused_layers no)
			(net "GND")
			(clearance 0)
		)
		(pad "19" thru_hole circle
			(at 0 45.72 270)
			(size 1.6256 1.6256)
			(drill 1.1176)
			(layers "*.Cu" "*.Mask")
			(remove_unused_layers no)
			(net "GND")
			(clearance 0)
		)
		(pad "20" thru_hole circle
			(at 0 48.26 270)
			(size 1.6256 1.6256)
			(drill 1.1176)
			(layers "*.Cu" "*.Mask")
			(remove_unused_layers no)
			(net "GND")
			(clearance 0)
		)
		(pad "21" thru_hole circle
			(at 0 50.8 270)
			(size 1.6256 1.6256)
			(drill 1.1176)
			(layers "*.Cu" "*.Mask")
			(remove_unused_layers no)
			(net "GND")
			(clearance 0)
		)
		(pad "22" thru_hole circle
			(at 0 53.34 270)
			(size 1.6256 1.6256)
			(drill 1.1176)
			(layers "*.Cu" "*.Mask")
			(remove_unused_layers no)
			(net "GND")
			(clearance 0)
		)
		(pad "23" thru_hole circle
			(at 0 55.88 270)
			(size 1.6256 1.6256)
			(drill 1.1176)
			(layers "*.Cu" "*.Mask")
			(remove_unused_layers no)
			(net "GND")
			(clearance 0)
		)
		(pad "24" thru_hole circle
			(at 0 58.42 270)
			(size 1.6256 1.6256)
			(drill 1.1176)
			(layers "*.Cu" "*.Mask")
			(remove_unused_layers no)
			(net "GND")
			(clearance 0)
		)
		(pad "25" thru_hole circle
			(at 0 60.96 270)
			(size 1.6256 1.6256)
			(drill 1.1176)
			(layers "*.Cu" "*.Mask")
			(remove_unused_layers no)
			(net "PHLOSS")
			(clearance 0)
		)
		(pad "26" thru_hole circle
			(at 0 63.5 270)
			(size 1.6256 1.6256)
			(drill 1.1176)
			(layers "*.Cu" "*.Mask")
			(remove_unused_layers no)
			(net "PSU1_REMOTE_N")
			(clearance 0)
		)
		(pad "27" thru_hole circle
			(at 0 66.04 270)
			(size 1.6256 1.6256)
			(drill 1.1176)
			(layers "*.Cu" "*.Mask")
			(remove_unused_layers no)
			(net "PSU1_AC_OK")
			(clearance 0)
		)
		(pad "28" thru_hole circle
			(at 0 68.58 270)
			(size 1.6256 1.6256)
			(drill 1.1176)
			(layers "*.Cu" "*.Mask")
			(remove_unused_layers no)
			(net "PSU1_CSAHRE")
			(clearance 0)
		)
		(pad "29" thru_hole circle
			(at 0 71.12 270)
			(size 1.6256 1.6256)
			(drill 1.1176)
			(layers "*.Cu" "*.Mask")
			(remove_unused_layers no)
			(net "PSU1_PS_ON_N")
			(clearance 0)
		)
		(pad "30" thru_hole circle
			(at 0 73.66 270)
			(size 1.6256 1.6256)
			(drill 1.1176)
			(layers "*.Cu" "*.Mask")
			(remove_unused_layers no)
			(net "PSU1_PS_KILL")
			(clearance 0)
		)
		(pad "31" thru_hole circle
			(at 0 76.2 270)
			(size 1.6256 1.6256)
			(drill 1.1176)
			(layers "*.Cu" "*.Mask")
			(remove_unused_layers no)
			(net "PSU1_RESET")
			(clearance 0)
		)
		(pad "32" thru_hole circle
			(at 0 78.74 270)
			(size 1.6256 1.6256)
			(drill 1.1176)
			(layers "*.Cu" "*.Mask")
			(remove_unused_layers no)
			(net "PSU_ALERT_N")
			(clearance 0)
		)
		(pad "33" thru_hole circle
			(at 5.08 78.74 270)
			(size 1.6256 1.6256)
			(drill 1.1176)
			(layers "*.Cu" "*.Mask")
			(remove_unused_layers no)
			(net "I2C_PSU1_SDA")
			(clearance 0)
		)
		(pad "34" thru_hole circle
			(at 5.08 76.2 270)
			(size 1.6256 1.6256)
			(drill 1.1176)
			(layers "*.Cu" "*.Mask")
			(remove_unused_layers no)
			(net "Net_430")
			(clearance 0)
		)
		(pad "35" thru_hole circle
			(at 5.08 73.66 270)
			(size 1.6256 1.6256)
			(drill 1.1176)
			(layers "*.Cu" "*.Mask")
			(remove_unused_layers no)
			(net "I2C_PSU1_SCL")
			(clearance 0)
		)
		(pad "36" thru_hole circle
			(at 5.08 71.12 270)
			(size 1.6256 1.6256)
			(drill 1.1176)
			(layers "*.Cu" "*.Mask")
			(remove_unused_layers no)
			(net "PSU1_RETURN")
			(clearance 0)
		)
		(pad "37" thru_hole circle
			(at 5.08 68.58 270)
			(size 1.6256 1.6256)
			(drill 1.1176)
			(layers "*.Cu" "*.Mask")
			(remove_unused_layers no)
			(net "PSU1_DC_OK")
			(clearance 0)
		)
		(pad "38" thru_hole circle
			(at 5.08 66.04 270)
			(size 1.6256 1.6256)
			(drill 1.1176)
			(layers "*.Cu" "*.Mask")
			(remove_unused_layers no)
			(net "PSU1_AD0")
			(clearance 0)
		)
		(pad "39" thru_hole circle
			(at 5.08 63.5 270)
			(size 1.6256 1.6256)
			(drill 1.1176)
			(layers "*.Cu" "*.Mask")
			(remove_unused_layers no)
			(net "P12V_STBY")
			(clearance 0)
		)
		(pad "40" thru_hole circle
			(at 5.08 60.96 270)
			(size 1.6256 1.6256)
			(drill 1.1176)
			(layers "*.Cu" "*.Mask")
			(remove_unused_layers no)
			(net "PSU1_REMOTE_P")
			(clearance 0)
		)
		(pad "41" thru_hole circle
			(at 5.08 58.42 270)
			(size 1.6256 1.6256)
			(drill 1.1176)
			(layers "*.Cu" "*.Mask")
			(remove_unused_layers no)
			(net "GND")
			(clearance 0)
		)
		(pad "42" thru_hole circle
			(at 5.08 55.88 270)
			(size 1.6256 1.6256)
			(drill 1.1176)
			(layers "*.Cu" "*.Mask")
			(remove_unused_layers no)
			(net "GND")
			(clearance 0)
		)
		(pad "43" thru_hole circle
			(at 5.08 53.34 270)
			(size 1.6256 1.6256)
			(drill 1.1176)
			(layers "*.Cu" "*.Mask")
			(remove_unused_layers no)
			(net "GND")
			(clearance 0)
		)
		(pad "44" thru_hole circle
			(at 5.08 50.8 270)
			(size 1.6256 1.6256)
			(drill 1.1176)
			(layers "*.Cu" "*.Mask")
			(remove_unused_layers no)
			(net "GND")
			(clearance 0)
		)
		(pad "45" thru_hole circle
			(at 5.08 48.26 270)
			(size 1.6256 1.6256)
			(drill 1.1176)
			(layers "*.Cu" "*.Mask")
			(remove_unused_layers no)
			(net "GND")
			(clearance 0)
		)
		(pad "46" thru_hole circle
			(at 5.08 45.72 270)
			(size 1.6256 1.6256)
			(drill 1.1176)
			(layers "*.Cu" "*.Mask")
			(remove_unused_layers no)
			(net "GND")
			(clearance 0)
		)
		(pad "47" thru_hole circle
			(at 5.08 43.18 270)
			(size 1.6256 1.6256)
			(drill 1.1176)
			(layers "*.Cu" "*.Mask")
			(remove_unused_layers no)
			(net "GND")
			(clearance 0)
		)
		(pad "48" thru_hole circle
			(at 5.08 40.64 270)
			(size 1.6256 1.6256)
			(drill 1.1176)
			(layers "*.Cu" "*.Mask")
			(remove_unused_layers no)
			(net "GND")
			(clearance 0)
		)
		(pad "49" thru_hole circle
			(at 5.08 38.1 270)
			(size 1.6256 1.6256)
			(drill 1.1176)
			(layers "*.Cu" "*.Mask")
			(remove_unused_layers no)
			(net "GND")
			(clearance 0)
		)
		(pad "50" thru_hole circle
			(at 5.08 35.56 270)
			(size 1.6256 1.6256)
			(drill 1.1176)
			(layers "*.Cu" "*.Mask")
			(remove_unused_layers no)
			(net "GND")
			(clearance 0)
		)
		(pad "51" thru_hole circle
			(at 5.08 33.02 270)
			(size 1.6256 1.6256)
			(drill 1.1176)
			(layers "*.Cu" "*.Mask")
			(remove_unused_layers no)
			(net "GND")
			(clearance 0)
		)
		(pad "52" thru_hole circle
			(at 5.08 30.48 270)
			(size 1.6256 1.6256)
			(drill 1.1176)
			(layers "*.Cu" "*.Mask")
			(remove_unused_layers no)
			(net "GND")
			(clearance 0)
		)
		(pad "53" thru_hole circle
			(at 5.08 27.94 270)
			(size 1.6256 1.6256)
			(drill 1.1176)
			(layers "*.Cu" "*.Mask")
			(remove_unused_layers no)
			(net "P12V")
			(clearance 0)
		)
		(pad "54" thru_hole circle
			(at 5.08 25.4 270)
			(size 1.6256 1.6256)
			(drill 1.1176)
			(layers "*.Cu" "*.Mask")
			(remove_unused_layers no)
			(net "P12V")
			(clearance 0)
		)
		(pad "55" thru_hole circle
			(at 5.08 22.86 270)
			(size 1.6256 1.6256)
			(drill 1.1176)
			(layers "*.Cu" "*.Mask")
			(remove_unused_layers no)
			(net "P12V")
			(clearance 0)
		)
		(pad "56" thru_hole circle
			(at 5.08 20.32 270)
			(size 1.6256 1.6256)
			(drill 1.1176)
			(layers "*.Cu" "*.Mask")
			(remove_unused_layers no)
			(net "P12V")
			(clearance 0)
		)
		(pad "57" thru_hole circle
			(at 5.08 17.78 270)
			(size 1.6256 1.6256)
			(drill 1.1176)
			(layers "*.Cu" "*.Mask")
			(remove_unused_layers no)
			(net "P12V")
			(clearance 0)
		)
		(pad "58" thru_hole circle
			(at 5.08 15.24 270)
			(size 1.6256 1.6256)
			(drill 1.1176)
			(layers "*.Cu" "*.Mask")
			(remove_unused_layers no)
			(net "P12V")
			(clearance 0)
		)
		(pad "59" thru_hole circle
			(at 5.08 12.7 270)
			(size 1.6256 1.6256)
			(drill 1.1176)
			(layers "*.Cu" "*.Mask")
			(remove_unused_layers no)
			(net "P12V")
			(clearance 0)
		)
		(pad "60" thru_hole circle
			(at 5.08 10.16 270)
			(size 1.6256 1.6256)
			(drill 1.1176)
			(layers "*.Cu" "*.Mask")
			(remove_unused_layers no)
			(net "P12V")
			(clearance 0)
		)
		(pad "61" thru_hole circle
			(at 5.08 7.62 270)
			(size 1.6256 1.6256)
			(drill 1.1176)
			(layers "*.Cu" "*.Mask")
			(remove_unused_layers no)
			(net "P12V")
			(clearance 0)
		)
		(pad "62" thru_hole circle
			(at 5.08 5.08 270)
			(size 1.6256 1.6256)
			(drill 1.1176)
			(layers "*.Cu" "*.Mask")
			(remove_unused_layers no)
			(net "P12V")
			(clearance 0)
		)
		(pad "63" thru_hole circle
			(at 5.08 2.54 270)
			(size 1.6256 1.6256)
			(drill 1.1176)
			(layers "*.Cu" "*.Mask")
			(remove_unused_layers no)
			(net "P12V")
			(clearance 0)
		)
		(pad "64" thru_hole circle
			(at 5.08 0 270)
			(size 1.6256 1.6256)
			(drill 1.1176)
			(layers "*.Cu" "*.Mask")
			(remove_unused_layers no)
			(net "P12V")
			(clearance 0)
		)
	)
)
